# S9S_MB_2U (Grand Teton) — schematic netlist excerpt (pin names and nets, part order shuffled) for the footprints in the layout excerpt that follows; sources: Cadence DE-HDL packaged netlist, KiCad conversion of 03242023_DA0F0TMBIJ0_F0T_Motherboard_J_brd_V01_OCP.brd

U62  BAS70057F  BAS70-05-7-F IC  pkg SOT23_123XB  page 185
  B  = P3V_BAT_R
  A  = P3V3_AUX
  C  = P3V3_RTC_AUX

R3281  Q_RES  1K 1% EMPTY  pkg 0402LF  page 166 : A = FM_P2E_EQB1 ; B = GND
C567  Q_CAP  0.1UF 25V 10% X7R  pkg 0402  page 236 : A = PVNN_TERM_CPU0 ; B = GND

(kicad_pcb
	(version 20260206)
	(generator "pcbnew")
	(generator_version "10.0")
	(general
		(thickness 1.6)
		(legacy_teardrops no)
	)
	(paper "A4")
	(title_block
		(title "03242023_DA0F0TMBIJ0_F0T_Motherboard_J_brd_V01_OCP.brd")
		(comment 1 "Grand Teton / footprints 2172-2174 of 6105")
	)
	(layers
		(0 "F.Cu" signal "TOP")
		(4 "In1.Cu" signal "GND")
		(6 "In2.Cu" signal "IN1")
		(8 "In3.Cu" signal "GND1")
		(10 "In4.Cu" signal "IN2")
		(12 "In5.Cu" signal "GND2")
		(14 "In6.Cu" signal "IN3")
		(16 "In7.Cu" signal "GND3")
		(18 "In8.Cu" signal "VCC")
		(20 "In9.Cu" signal "VCC1")
		(22 "In10.Cu" signal "GND4")
		(24 "In11.Cu" signal "IN4")
		(26 "In12.Cu" signal "GND5")
		(28 "In13.Cu" signal "IN5")
		(30 "In14.Cu" signal "GND6")
		(32 "In15.Cu" signal "IN6")
		(34 "In16.Cu" signal "GND7")
		(2 "B.Cu" signal "BOTTOM")
		(9 "F.Adhes" user "F.Adhesive")
		(11 "B.Adhes" user "B.Adhesive")
		(13 "F.Paste" user "Package Geometry/Pastemask Top")
		(15 "B.Paste" user "Package Geometry/Pastemask Bottom")
		(5 "F.SilkS" user "Ref Des/Silkscreen Top")
		(7 "B.SilkS" user "Ref Des/Silkscreen Bottom")
		(1 "F.Mask" user "Board Geometry/Soldermask Top")
		(3 "B.Mask" user "Board Geometry/Soldermask Bottom")
		(17 "Dwgs.User" user "User.Drawings")
		(19 "Cmts.User" user "User.Comments")
		(21 "Eco1.User" user "User.Eco1")
		(23 "Eco2.User" user "User.Eco2")
		(25 "Edge.Cuts" user "Board Geometry/Outline")
		(27 "Margin" user)
		(31 "F.CrtYd" user "Package Geometry/Place Bound Top")
		(29 "B.CrtYd" user "Package Geometry/Place Bound Bottom")
		(35 "F.Fab" user "Ref Des/Assembly Top")
		(33 "B.Fab" user "Ref Des/Assembly Bottom")
	)
	(footprint ""
		(layer "F.Cu")
		(at 27.628596 -396.390876)
		(property "Reference" "R3281"
			(at 0 0 0)
			(layer "F.SilkS")
			(hide yes)
			(effects
				(font
					(size 1.27 1.27)
				)
			)
		)
		(property "Value" ""
			(at 0 0 0)
			(layer "F.Fab")
			(effects
				(font
					(size 1.27 1.27)
				)
			)
		)
		(duplicate_pad_numbers_are_jumpers no)
		(fp_line
			(start -0.7874 -0.4064)
			(end 0.7874 -0.4064)
			(stroke
				(width 0.1524)
				(type default)
			)
			(layer "F.SilkS")
		)
		(fp_line
			(start -0.7874 0.4064)
			(end -0.7874 -0.4064)
			(stroke
				(width 0.1524)
				(type default)
			)
			(layer "F.SilkS")
		)
		(fp_line
			(start 0.7874 -0.4064)
			(end 0.7874 0.4064)
			(stroke
				(width 0.1524)
				(type default)
			)
			(layer "F.SilkS")
		)
		(fp_line
			(start 0.7874 0.4064)
			(end -0.7874 0.4064)
			(stroke
				(width 0.1524)
				(type default)
			)
			(layer "F.SilkS")
		)
		(fp_line
			(start -0.67945 -0.305054)
			(end -0.12065 -0.305054)
			(stroke
				(width 0.1)
				(type default)
			)
			(layer "F.Fab")
		)
		(fp_line
			(start -0.67945 0.3048)
			(end -0.67945 -0.305054)
			(stroke
				(width 0.1)
				(type default)
			)
			(layer "F.Fab")
		)
		(fp_line
			(start -0.12065 -0.305054)
			(end -0.12065 -0.2794)
			(stroke
				(width 0.1)
				(type default)
			)
			(layer "F.Fab")
		)
		(fp_line
			(start -0.12065 -0.2794)
			(end 0.12065 -0.2794)
			(stroke
				(width 0.1)
				(type default)
			)
			(layer "F.Fab")
		)
		(fp_line
			(start -0.12065 0.2794)
			(end -0.12065 0.3048)
			(stroke
				(width 0.1)
				(type default)
			)
			(layer "F.Fab")
		)
		(fp_line
			(start -0.12065 0.3048)
			(end -0.67945 0.3048)
			(stroke
				(width 0.1)
				(type default)
			)
			(layer "F.Fab")
		)
		(fp_line
			(start 0.120396 0.2794)
			(end -0.12065 0.2794)
			(stroke
				(width 0.1)
				(type default)
			)
			(layer "F.Fab")
		)
		(fp_line
			(start 0.120396 0.3048)
			(end 0.120396 0.2794)
			(stroke
				(width 0.1)
				(type default)
			)
			(layer "F.Fab")
		)
		(fp_line
			(start 0.12065 -0.3048)
			(end 0.67945 -0.3048)
			(stroke
				(width 0.1)
				(type default)
			)
			(layer "F.Fab")
		)
		(fp_line
			(start 0.12065 -0.2794)
			(end 0.12065 -0.3048)
			(stroke
				(width 0.1)
				(type default)
			)
			(layer "F.Fab")
		)
		(fp_line
			(start 0.67945 -0.3048)
			(end 0.67945 0.3048)
			(stroke
				(width 0.1)
				(type default)
			)
			(layer "F.Fab")
		)
		(fp_line
			(start 0.67945 0.3048)
			(end 0.120396 0.3048)
			(stroke
				(width 0.1)
				(type default)
			)
			(layer "F.Fab")
		)
		(pad "1" smd circle
			(at -0.40005 0)
			(size 0 0)
			(layers "F.Cu" "F.Mask" "F.Paste")
			(net "FM_P2E_EQB1")
		)
		(pad "2" smd circle
			(at 0.40005 0)
			(size 0 0)
			(layers "F.Cu" "F.Mask" "F.Paste")
			(net "GND")
		)
	)
	(footprint ""
		(layer "F.Cu")
		(at 395.550898 -160.13049 90)
		(property "Reference" "C567"
			(at 0 0 90)
			(layer "F.SilkS")
			(hide yes)
			(effects
				(font
					(size 1.27 1.27)
				)
			)
		)
		(property "Value" ""
			(at 0 0 90)
			(layer "F.Fab")
			(effects
				(font
					(size 1.27 1.27)
				)
			)
		)
		(duplicate_pad_numbers_are_jumpers no)
		(fp_line
			(start 0.7874 -0.4064)
			(end 0.7874 0.4064)
			(stroke
				(width 0.1524)
				(type default)
			)
			(layer "F.SilkS")
		)
		(fp_line
			(start -0.7874 -0.4064)
			(end 0.7874 -0.4064)
			(stroke
				(width 0.1524)
				(type default)
			)
			(layer "F.SilkS")
		)
		(fp_line
			(start 0.7874 0.4064)
			(end -0.7874 0.4064)
			(stroke
				(width 0.1524)
				(type default)
			)
			(layer "F.SilkS")
		)
		(fp_line
			(start -0.7874 0.4064)
			(end -0.7874 -0.4064)
			(stroke
				(width 0.1524)
				(type default)
			)
			(layer "F.SilkS")
		)
		(fp_line
			(start -0.12065 -0.305054)
			(end -0.12065 -0.2794)
			(stroke
				(width 0.1)
				(type default)
			)
			(layer "F.Fab")
		)
		(fp_line
			(start -0.67945 -0.305054)
			(end -0.12065 -0.305054)
			(stroke
				(width 0.1)
				(type default)
			)
			(layer "F.Fab")
		)
		(fp_line
			(start 0.67945 -0.3048)
			(end 0.67945 0.3048)
			(stroke
				(width 0.1)
				(type default)
			)
			(layer "F.Fab")
		)
		(fp_line
			(start 0.12065 -0.3048)
			(end 0.67945 -0.3048)
			(stroke
				(width 0.1)
				(type default)
			)
			(layer "F.Fab")
		)
		(fp_line
			(start 0.12065 -0.2794)
			(end 0.12065 -0.3048)
			(stroke
				(width 0.1)
				(type default)
			)
			(layer "F.Fab")
		)
		(fp_line
			(start -0.12065 -0.2794)
			(end 0.12065 -0.2794)
			(stroke
				(width 0.1)
				(type default)
			)
			(layer "F.Fab")
		)
		(fp_line
			(start 0.120396 0.2794)
			(end -0.12065 0.2794)
			(stroke
				(width 0.1)
				(type default)
			)
			(layer "F.Fab")
		)
		(fp_line
			(start -0.12065 0.2794)
			(end -0.12065 0.3048)
			(stroke
				(width 0.1)
				(type default)
			)
			(layer "F.Fab")
		)
		(fp_line
			(start 0.67945 0.3048)
			(end 0.120396 0.3048)
			(stroke
				(width 0.1)
				(type default)
			)
			(layer "F.Fab")
		)
		(fp_line
			(start 0.120396 0.3048)
			(end 0.120396 0.2794)
			(stroke
				(width 0.1)
				(type default)
			)
			(layer "F.Fab")
		)
		(fp_line
			(start -0.12065 0.3048)
			(end -0.67945 0.3048)
			(stroke
				(width 0.1)
				(type default)
			)
			(layer "F.Fab")
		)
		(fp_line
			(start -0.67945 0.3048)
			(end -0.67945 -0.305054)
			(stroke
				(width 0.1)
				(type default)
			)
			(layer "F.Fab")
		)
		(pad "1" smd circle
			(at -0.40005 0 90)
			(size 0 0)
			(layers "F.Cu" "F.Mask" "F.Paste")
			(net "PVNN_TERM_CPU0")
		)
		(pad "2" smd circle
			(at 0.40005 0 90)
			(size 0 0)
			(layers "F.Cu" "F.Mask" "F.Paste")
			(net "GND")
		)
	)
	(footprint ""
		(layer "F.Cu")
		(at 303.457102 -28.997656 90)
		(property "Reference" "U62"
			(at 1.246378 -4.518914 0)
			(unlocked yes)
			(layer "F.SilkS")
			(effects
				(font
					(size 0.7874 0.5842)
					(thickness 0.1524)
				)
				(justify left)
			)
		)
		(property "Value" ""
			(at 0 0 90)
			(layer "F.Fab")
			(effects
				(font
					(size 1.27 1.27)
				)
			)
		)
		(duplicate_pad_numbers_are_jumpers no)
		(fp_line
			(start 1.584198 -1.500124)
			(end -1.584198 -1.500124)
			(stroke
				(width 0.1524)
				(type default)
			)
			(layer "F.SilkS")
		)
		(fp_line
			(start -1.584198 -1.500124)
			(end -1.584198 1.500124)
			(stroke
				(width 0.1524)
				(type default)
			)
			(layer "F.SilkS")
		)
		(fp_line
			(start 1.584198 1.500124)
			(end 1.584198 -1.500124)
			(stroke
				(width 0.1524)
				(type default)
			)
			(layer "F.SilkS")
		)
		(fp_line
			(start -1.584198 1.500124)
			(end 1.584198 1.500124)
			(stroke
				(width 0.1524)
				(type default)
			)
			(layer "F.SilkS")
		)
		(fp_line
			(start 0.700024 -1.500124)
			(end -0.700024 -1.500124)
			(stroke
				(width 0.1)
				(type default)
			)
			(layer "F.Fab")
		)
		(fp_line
			(start -0.700024 -1.500124)
			(end -0.700024 1.500124)
			(stroke
				(width 0.1)
				(type default)
			)
			(layer "F.Fab")
		)
		(fp_line
			(start 0.700024 1.500124)
			(end 0.700024 -1.500124)
			(stroke
				(width 0.1)
				(type default)
			)
			(layer "F.Fab")
		)
		(fp_line
			(start -0.700024 1.500124)
			(end 0.700024 1.500124)
			(stroke
				(width 0.1)
				(type default)
			)
			(layer "F.Fab")
		)
		(pad "1" smd rect
			(at -0.999998 -0.94996)
			(size 0.8128 0.9144)
			(layers "F.Cu" "F.Mask" "F.Paste")
			(net "P3V_BAT_R")
		)
		(pad "2" smd rect
			(at -0.999998 0.94996)
			(size 0.8128 0.9144)
			(layers "F.Cu" "F.Mask" "F.Paste")
			(net "P3V3_AUX")
		)
		(pad "3" smd rect
			(at 0.999998 0)
			(size 0.8128 0.9144)
			(layers "F.Cu" "F.Mask" "F.Paste")
			(net "P3V3_RTC_AUX")
		)
	)
)
